(kicad_pcb
	(version 20260206)
	(generator "pcbnew")
	(generator_version "10.0")
	(general
		(thickness 1.6)
		(legacy_teardrops no)
	)
	(paper "A4")
	(title_block
		(title "03242023_DA0F0TMBIJ0_F0T_Motherboard_J_brd_V01_OCP.brd")
		(comment 1 "Grand Teton / footprint 3198 of 6105 (J12), pads 113-224 of 291")
	)
	(layers
		(0 "F.Cu" signal "TOP")
		(4 "In1.Cu" signal "GND")
		(6 "In2.Cu" signal "IN1")
		(8 "In3.Cu" signal "GND1")
		(10 "In4.Cu" signal "IN2")
		(12 "In5.Cu" signal "GND2")
		(14 "In6.Cu" signal "IN3")
		(16 "In7.Cu" signal "GND3")
		(18 "In8.Cu" signal "VCC")
		(20 "In9.Cu" signal "VCC1")
		(22 "In10.Cu" signal "GND4")
		(24 "In11.Cu" signal "IN4")
		(26 "In12.Cu" signal "GND5")
		(28 "In13.Cu" signal "IN5")
		(30 "In14.Cu" signal "GND6")
		(32 "In15.Cu" signal "IN6")
		(34 "In16.Cu" signal "GND7")
		(2 "B.Cu" signal "BOTTOM")
		(9 "F.Adhes" user "F.Adhesive")
		(11 "B.Adhes" user "B.Adhesive")
		(13 "F.Paste" user "Package Geometry/Pastemask Top")
		(15 "B.Paste" user "Package Geometry/Pastemask Bottom")
		(5 "F.SilkS" user "Ref Des/Silkscreen Top")
		(7 "B.SilkS" user "Ref Des/Silkscreen Bottom")
		(1 "F.Mask" user "Board Geometry/Soldermask Top")
		(3 "B.Mask" user "Board Geometry/Soldermask Bottom")
		(17 "Dwgs.User" user "User.Drawings")
		(19 "Cmts.User" user "User.Comments")
		(21 "Eco1.User" user "User.Eco1")
		(23 "Eco2.User" user "User.Eco2")
		(25 "Edge.Cuts" user "Board Geometry/Outline")
		(27 "Margin" user)
		(31 "F.CrtYd" user "Package Geometry/Place Bound Top")
		(29 "B.CrtYd" user "Package Geometry/Place Bound Bottom")
		(35 "F.Fab" user "Ref Des/Assembly Top")
		(33 "B.Fab" user "Ref Des/Assembly Bottom")
	)
	(footprint ""
		(layer "F.Cu")
		(at 423.890948 -258.091686)
		(property "Reference" "J12"
			(at -3.683 -81.702148 0)
			(unlocked yes)
			(layer "F.SilkS")
			(effects
				(font
					(size 0.7874 0.5842)
					(thickness 0.1524)
				)
				(justify left)
			)
		)
		(property "Value" ""
			(at 0 0 0)
			(layer "F.Fab")
			(effects
				(font
					(size 1.27 1.27)
				)
			)
		)
		(duplicate_pad_numbers_are_jumpers no)
		(pad "113" smd rect
			(at -2.050034 36.975034 270)
			(size 0.519938 1.4986)
			(layers "F.Cu" "F.Mask" "F.Paste")
			(net "M_F_CPU0_SB_DQ<9>")
		)
		(pad "114" smd rect
			(at -2.050034 37.824918 270)
			(size 0.519938 1.4986)
			(layers "F.Cu" "F.Mask" "F.Paste")
			(net "GND")
		)
		(pad "115" smd rect
			(at -2.050034 38.675056 270)
			(size 0.519938 1.4986)
			(layers "F.Cu" "F.Mask" "F.Paste")
			(net "M_F_CPU0_SB_DQS_DP<1>")
		)
		(pad "116" smd rect
			(at -2.050034 39.52494 270)
			(size 0.519938 1.4986)
			(layers "F.Cu" "F.Mask" "F.Paste")
			(net "M_F_CPU0_SB_DQS_DN<1>")
		)
		(pad "117" smd rect
			(at -2.050034 40.375078 270)
			(size 0.519938 1.4986)
			(layers "F.Cu" "F.Mask" "F.Paste")
			(net "GND")
		)
		(pad "118" smd rect
			(at -2.050034 41.224962 270)
			(size 0.519938 1.4986)
			(layers "F.Cu" "F.Mask" "F.Paste")
			(net "M_F_CPU0_SB_DQ<12>")
		)
		(pad "119" smd rect
			(at -2.050034 42.0751 270)
			(size 0.519938 1.4986)
			(layers "F.Cu" "F.Mask" "F.Paste")
			(net "GND")
		)
		(pad "120" smd rect
			(at -2.050034 42.924984 270)
			(size 0.519938 1.4986)
			(layers "F.Cu" "F.Mask" "F.Paste")
			(net "M_F_CPU0_SB_DQ<13>")
		)
		(pad "121" smd rect
			(at -2.050034 43.775122 270)
			(size 0.519938 1.4986)
			(layers "F.Cu" "F.Mask" "F.Paste")
			(net "GND")
		)
		(pad "122" smd rect
			(at -2.050034 44.625006 270)
			(size 0.519938 1.4986)
			(layers "F.Cu" "F.Mask" "F.Paste")
			(net "M_F_CPU0_SB_DQ<16>")
		)
		(pad "123" smd rect
			(at -2.050034 45.47489 270)
			(size 0.519938 1.4986)
			(layers "F.Cu" "F.Mask" "F.Paste")
			(net "GND")
		)
		(pad "124" smd rect
			(at -2.050034 46.325028 270)
			(size 0.519938 1.4986)
			(layers "F.Cu" "F.Mask" "F.Paste")
			(net "M_F_CPU0_SB_DQ<17>")
		)
		(pad "125" smd rect
			(at -2.050034 47.174912 270)
			(size 0.519938 1.4986)
			(layers "F.Cu" "F.Mask" "F.Paste")
			(net "GND")
		)
		(pad "126" smd rect
			(at -2.050034 48.02505 270)
			(size 0.519938 1.4986)
			(layers "F.Cu" "F.Mask" "F.Paste")
			(net "M_F_CPU0_SB_DQS_DP<2>")
		)
		(pad "127" smd rect
			(at -2.050034 48.874934 270)
			(size 0.519938 1.4986)
			(layers "F.Cu" "F.Mask" "F.Paste")
			(net "M_F_CPU0_SB_DQS_DN<2>")
		)
		(pad "128" smd rect
			(at -2.050034 49.725072 270)
			(size 0.519938 1.4986)
			(layers "F.Cu" "F.Mask" "F.Paste")
			(net "GND")
		)
		(pad "129" smd rect
			(at -2.050034 50.574956 270)
			(size 0.519938 1.4986)
			(layers "F.Cu" "F.Mask" "F.Paste")
			(net "M_F_CPU0_SB_DQ<20>")
		)
		(pad "130" smd rect
			(at -2.050034 51.425094 270)
			(size 0.519938 1.4986)
			(layers "F.Cu" "F.Mask" "F.Paste")
			(net "GND")
		)
		(pad "131" smd rect
			(at -2.050034 52.274978 270)
			(size 0.519938 1.4986)
			(layers "F.Cu" "F.Mask" "F.Paste")
			(net "M_F_CPU0_SB_DQ<21>")
		)
		(pad "132" smd rect
			(at -2.050034 53.125116 270)
			(size 0.519938 1.4986)
			(layers "F.Cu" "F.Mask" "F.Paste")
			(net "GND")
		)
		(pad "133" smd rect
			(at -2.050034 53.975 270)
			(size 0.519938 1.4986)
			(layers "F.Cu" "F.Mask" "F.Paste")
			(net "M_F_CPU0_SB_DQ<24>")
		)
		(pad "134" smd rect
			(at -2.050034 54.824884 270)
			(size 0.519938 1.4986)
			(layers "F.Cu" "F.Mask" "F.Paste")
			(net "GND")
		)
		(pad "135" smd rect
			(at -2.050034 55.675022 270)
			(size 0.519938 1.4986)
			(layers "F.Cu" "F.Mask" "F.Paste")
			(net "M_F_CPU0_SB_DQ<25>")
		)
		(pad "136" smd rect
			(at -2.050034 56.524906 270)
			(size 0.519938 1.4986)
			(layers "F.Cu" "F.Mask" "F.Paste")
			(net "GND")
		)
		(pad "137" smd rect
			(at -2.050034 57.375044 270)
			(size 0.519938 1.4986)
			(layers "F.Cu" "F.Mask" "F.Paste")
			(net "M_F_CPU0_SB_DQS_DP<3>")
		)
		(pad "138" smd rect
			(at -2.050034 58.224928 270)
			(size 0.519938 1.4986)
			(layers "F.Cu" "F.Mask" "F.Paste")
			(net "M_F_CPU0_SB_DQS_DN<3>")
		)
		(pad "139" smd rect
			(at -2.050034 59.075066 270)
			(size 0.519938 1.4986)
			(layers "F.Cu" "F.Mask" "F.Paste")
			(net "GND")
		)
		(pad "140" smd rect
			(at -2.050034 59.92495 270)
			(size 0.519938 1.4986)
			(layers "F.Cu" "F.Mask" "F.Paste")
			(net "M_F_CPU0_SB_DQ<28>")
		)
		(pad "141" smd rect
			(at -2.050034 60.775088 270)
			(size 0.519938 1.4986)
			(layers "F.Cu" "F.Mask" "F.Paste")
			(net "GND")
		)
		(pad "142" smd rect
			(at -2.050034 61.624972 270)
			(size 0.519938 1.4986)
			(layers "F.Cu" "F.Mask" "F.Paste")
			(net "M_F_CPU0_SB_DQ<29>")
		)
		(pad "143" smd rect
			(at -2.050034 62.47511 270)
			(size 0.519938 1.4986)
			(layers "F.Cu" "F.Mask" "F.Paste")
			(net "GND")
		)
		(pad "144" smd rect
			(at -2.050034 63.324994 270)
			(size 0.519938 1.4986)
			(layers "F.Cu" "F.Mask" "F.Paste")
			(net "TP_CHF_CPU0_DIMM2_FRU_1")
		)
		(pad "145" smd rect
			(at 2.050034 -63.324994 270)
			(size 0.519938 1.4986)
			(layers "F.Cu" "F.Mask" "F.Paste")
			(net "P12V_S3_AUX_CPU0_NVDIMM")
		)
		(pad "146" smd rect
			(at 2.050034 -62.47511 270)
			(size 0.519938 1.4986)
			(layers "F.Cu" "F.Mask" "F.Paste")
			(net "P12V_S3_AUX_CPU0_NVDIMM")
		)
		(pad "147" smd rect
			(at 2.050034 -61.624972 270)
			(size 0.519938 1.4986)
			(layers "F.Cu" "F.Mask" "F.Paste")
			(net "PWRGD_CHF_CPU0_DIMM2")
		)
		(pad "148" smd rect
			(at 2.050034 -60.775088 270)
			(size 0.519938 1.4986)
			(layers "F.Cu" "F.Mask" "F.Paste")
			(net "PD_CHF_CPU0_DIMM2_SAA")
		)
		(pad "149" smd rect
			(at 2.050034 -59.92495 270)
			(size 0.519938 1.4986)
			(layers "F.Cu" "F.Mask" "F.Paste")
			(net "TP_CHF_CPU0_DIMM2_FRU_2")
		)
		(pad "150" smd rect
			(at 2.050034 -59.075066 270)
			(size 0.519938 1.4986)
			(layers "F.Cu" "F.Mask" "F.Paste")
			(net "TP_CHF_CPU0_DIMM2_FRU_3")
		)
		(pad "151" smd rect
			(at 2.050034 -58.224928 270)
			(size 0.519938 1.4986)
			(layers "F.Cu" "F.Mask" "F.Paste")
			(net "GND")
		)
		(pad "152" smd rect
			(at 2.050034 -57.375044 270)
			(size 0.519938 1.4986)
			(layers "F.Cu" "F.Mask" "F.Paste")
			(net "M_F_CPU0_SA_DQ<2>")
		)
		(pad "153" smd rect
			(at 2.050034 -56.524906 270)
			(size 0.519938 1.4986)
			(layers "F.Cu" "F.Mask" "F.Paste")
			(net "GND")
		)
		(pad "154" smd rect
			(at 2.050034 -55.675022 270)
			(size 0.519938 1.4986)
			(layers "F.Cu" "F.Mask" "F.Paste")
			(net "M_F_CPU0_SA_DQ<3>")
		)
		(pad "155" smd rect
			(at 2.050034 -54.824884 270)
			(size 0.519938 1.4986)
			(layers "F.Cu" "F.Mask" "F.Paste")
			(net "GND")
		)
		(pad "156" smd rect
			(at 2.050034 -53.975 270)
			(size 0.519938 1.4986)
			(layers "F.Cu" "F.Mask" "F.Paste")
			(net "M_F_CPU0_SA_DQS_DN<5>")
		)
		(pad "157" smd rect
			(at 2.050034 -53.125116 270)
			(size 0.519938 1.4986)
			(layers "F.Cu" "F.Mask" "F.Paste")
			(net "M_F_CPU0_SA_DQS_DP<5>")
		)
		(pad "158" smd rect
			(at 2.050034 -52.274978 270)
			(size 0.519938 1.4986)
			(layers "F.Cu" "F.Mask" "F.Paste")
			(net "GND")
		)
		(pad "159" smd rect
			(at 2.050034 -51.425094 270)
			(size 0.519938 1.4986)
			(layers "F.Cu" "F.Mask" "F.Paste")
			(net "M_F_CPU0_SA_DQ<6>")
		)
		(pad "160" smd rect
			(at 2.050034 -50.574956 270)
			(size 0.519938 1.4986)
			(layers "F.Cu" "F.Mask" "F.Paste")
			(net "GND")
		)
		(pad "161" smd rect
			(at 2.050034 -49.725072 270)
			(size 0.519938 1.4986)
			(layers "F.Cu" "F.Mask" "F.Paste")
			(net "M_F_CPU0_SA_DQ<7>")
		)
		(pad "162" smd rect
			(at 2.050034 -48.874934 270)
			(size 0.519938 1.4986)
			(layers "F.Cu" "F.Mask" "F.Paste")
			(net "GND")
		)
		(pad "163" smd rect
			(at 2.050034 -48.02505 270)
			(size 0.519938 1.4986)
			(layers "F.Cu" "F.Mask" "F.Paste")
			(net "M_F_CPU0_SA_DQ<10>")
		)
		(pad "164" smd rect
			(at 2.050034 -47.174912 270)
			(size 0.519938 1.4986)
			(layers "F.Cu" "F.Mask" "F.Paste")
			(net "GND")
		)
		(pad "165" smd rect
			(at 2.050034 -46.325028 270)
			(size 0.519938 1.4986)
			(layers "F.Cu" "F.Mask" "F.Paste")
			(net "M_F_CPU0_SA_DQ<11>")
		)
		(pad "166" smd rect
			(at 2.050034 -45.47489 270)
			(size 0.519938 1.4986)
			(layers "F.Cu" "F.Mask" "F.Paste")
			(net "GND")
		)
		(pad "167" smd rect
			(at 2.050034 -44.625006 270)
			(size 0.519938 1.4986)
			(layers "F.Cu" "F.Mask" "F.Paste")
			(net "M_F_CPU0_SA_DQS_DN<6>")
		)
		(pad "168" smd rect
			(at 2.050034 -43.775122 270)
			(size 0.519938 1.4986)
			(layers "F.Cu" "F.Mask" "F.Paste")
			(net "M_F_CPU0_SA_DQS_DP<6>")
		)
		(pad "169" smd rect
			(at 2.050034 -42.924984 270)
			(size 0.519938 1.4986)
			(layers "F.Cu" "F.Mask" "F.Paste")
			(net "GND")
		)
		(pad "170" smd rect
			(at 2.050034 -42.0751 270)
			(size 0.519938 1.4986)
			(layers "F.Cu" "F.Mask" "F.Paste")
			(net "M_F_CPU0_SA_DQ<14>")
		)
		(pad "171" smd rect
			(at 2.050034 -41.224962 270)
			(size 0.519938 1.4986)
			(layers "F.Cu" "F.Mask" "F.Paste")
			(net "GND")
		)
		(pad "172" smd rect
			(at 2.050034 -40.375078 270)
			(size 0.519938 1.4986)
			(layers "F.Cu" "F.Mask" "F.Paste")
			(net "M_F_CPU0_SA_DQ<15>")
		)
		(pad "173" smd rect
			(at 2.050034 -39.52494 270)
			(size 0.519938 1.4986)
			(layers "F.Cu" "F.Mask" "F.Paste")
			(net "GND")
		)
		(pad "174" smd rect
			(at 2.050034 -38.675056 270)
			(size 0.519938 1.4986)
			(layers "F.Cu" "F.Mask" "F.Paste")
			(net "M_F_CPU0_SA_DQ<18>")
		)
		(pad "175" smd rect
			(at 2.050034 -37.824918 270)
			(size 0.519938 1.4986)
			(layers "F.Cu" "F.Mask" "F.Paste")
			(net "GND")
		)
		(pad "176" smd rect
			(at 2.050034 -36.975034 270)
			(size 0.519938 1.4986)
			(layers "F.Cu" "F.Mask" "F.Paste")
			(net "M_F_CPU0_SA_DQ<19>")
		)
		(pad "177" smd rect
			(at 2.050034 -36.124896 270)
			(size 0.519938 1.4986)
			(layers "F.Cu" "F.Mask" "F.Paste")
			(net "GND")
		)
		(pad "178" smd rect
			(at 2.050034 -35.275012 270)
			(size 0.519938 1.4986)
			(layers "F.Cu" "F.Mask" "F.Paste")
			(net "M_F_CPU0_SA_DQS_DN<7>")
		)
		(pad "179" smd rect
			(at 2.050034 -34.425128 270)
			(size 0.519938 1.4986)
			(layers "F.Cu" "F.Mask" "F.Paste")
			(net "M_F_CPU0_SA_DQS_DP<7>")
		)
		(pad "180" smd rect
			(at 2.050034 -33.57499 270)
			(size 0.519938 1.4986)
			(layers "F.Cu" "F.Mask" "F.Paste")
			(net "GND")
		)
		(pad "181" smd rect
			(at 2.050034 -32.725106 270)
			(size 0.519938 1.4986)
			(layers "F.Cu" "F.Mask" "F.Paste")
			(net "M_F_CPU0_SA_DQ<22>")
		)
		(pad "182" smd rect
			(at 2.050034 -31.874968 270)
			(size 0.519938 1.4986)
			(layers "F.Cu" "F.Mask" "F.Paste")
			(net "GND")
		)
		(pad "183" smd rect
			(at 2.050034 -31.025084 270)
			(size 0.519938 1.4986)
			(layers "F.Cu" "F.Mask" "F.Paste")
			(net "M_F_CPU0_SA_DQ<23>")
		)
		(pad "184" smd rect
			(at 2.050034 -30.174946 270)
			(size 0.519938 1.4986)
			(layers "F.Cu" "F.Mask" "F.Paste")
			(net "GND")
		)
		(pad "185" smd rect
			(at 2.050034 -29.325062 270)
			(size 0.519938 1.4986)
			(layers "F.Cu" "F.Mask" "F.Paste")
			(net "M_F_CPU0_SA_DQ<26>")
		)
		(pad "186" smd rect
			(at 2.050034 -28.474924 270)
			(size 0.519938 1.4986)
			(layers "F.Cu" "F.Mask" "F.Paste")
			(net "GND")
		)
		(pad "187" smd rect
			(at 2.050034 -27.62504 270)
			(size 0.519938 1.4986)
			(layers "F.Cu" "F.Mask" "F.Paste")
			(net "M_F_CPU0_SA_DQ<27>")
		)
		(pad "188" smd rect
			(at 2.050034 -26.774902 270)
			(size 0.519938 1.4986)
			(layers "F.Cu" "F.Mask" "F.Paste")
			(net "GND")
		)
		(pad "189" smd rect
			(at 2.050034 -25.925018 270)
			(size 0.519938 1.4986)
			(layers "F.Cu" "F.Mask" "F.Paste")
			(net "M_F_CPU0_SA_DQS_DN<8>")
		)
		(pad "190" smd rect
			(at 2.050034 -25.07488 270)
			(size 0.519938 1.4986)
			(layers "F.Cu" "F.Mask" "F.Paste")
			(net "M_F_CPU0_SA_DQS_DP<8>")
		)
		(pad "191" smd rect
			(at 2.050034 -24.224996 270)
			(size 0.519938 1.4986)
			(layers "F.Cu" "F.Mask" "F.Paste")
			(net "GND")
		)
		(pad "192" smd rect
			(at 2.050034 -23.375112 270)
			(size 0.519938 1.4986)
			(layers "F.Cu" "F.Mask" "F.Paste")
			(net "M_F_CPU0_SA_DQ<30>")
		)
		(pad "193" smd rect
			(at 2.050034 -22.524974 270)
			(size 0.519938 1.4986)
			(layers "F.Cu" "F.Mask" "F.Paste")
			(net "GND")
		)
		(pad "194" smd rect
			(at 2.050034 -21.67509 270)
			(size 0.519938 1.4986)
			(layers "F.Cu" "F.Mask" "F.Paste")
			(net "M_F_CPU0_SA_DQ<31>")
		)
		(pad "195" smd rect
			(at 2.050034 -20.824952 270)
			(size 0.519938 1.4986)
			(layers "F.Cu" "F.Mask" "F.Paste")
			(net "GND")
		)
		(pad "196" smd rect
			(at 2.050034 -19.975068 270)
			(size 0.519938 1.4986)
			(layers "F.Cu" "F.Mask" "F.Paste")
			(net "M_F_CPU0_SA_CB<2>")
		)
		(pad "197" smd rect
			(at 2.050034 -19.12493 270)
			(size 0.519938 1.4986)
			(layers "F.Cu" "F.Mask" "F.Paste")
			(net "GND")
		)
		(pad "198" smd rect
			(at 2.050034 -18.275046 270)
			(size 0.519938 1.4986)
			(layers "F.Cu" "F.Mask" "F.Paste")
			(net "M_F_CPU0_SA_CB<3>")
		)
		(pad "199" smd rect
			(at 2.050034 -17.424908 270)
			(size 0.519938 1.4986)
			(layers "F.Cu" "F.Mask" "F.Paste")
			(net "GND")
		)
		(pad "200" smd rect
			(at 2.050034 -16.575024 270)
			(size 0.519938 1.4986)
			(layers "F.Cu" "F.Mask" "F.Paste")
			(net "M_F_CPU0_SA_DQS_DN<9>")
		)
		(pad "201" smd rect
			(at 2.050034 -15.724886 270)
			(size 0.519938 1.4986)
			(layers "F.Cu" "F.Mask" "F.Paste")
			(net "M_F_CPU0_SA_DQS_DP<9>")
		)
		(pad "202" smd rect
			(at 2.050034 -14.875002 270)
			(size 0.519938 1.4986)
			(layers "F.Cu" "F.Mask" "F.Paste")
			(net "GND")
		)
		(pad "203" smd rect
			(at 2.050034 -14.025118 270)
			(size 0.519938 1.4986)
			(layers "F.Cu" "F.Mask" "F.Paste")
			(net "M_F_CPU0_SA_CB<6>")
		)
		(pad "204" smd rect
			(at 2.050034 -13.17498 270)
			(size 0.519938 1.4986)
			(layers "F.Cu" "F.Mask" "F.Paste")
			(net "GND")
		)
		(pad "205" smd rect
			(at 2.050034 -12.325096 270)
			(size 0.519938 1.4986)
			(layers "F.Cu" "F.Mask" "F.Paste")
			(net "M_F_CPU0_SA_CB<7>")
		)
		(pad "206" smd rect
			(at 2.050034 -11.474958 270)
			(size 0.519938 1.4986)
			(layers "F.Cu" "F.Mask" "F.Paste")
			(net "GND")
		)
		(pad "207" smd rect
			(at 2.050034 -10.625074 270)
			(size 0.519938 1.4986)
			(layers "F.Cu" "F.Mask" "F.Paste")
			(net "RST_M_EF_CPU0_FPGA_N")
		)
		(pad "208" smd rect
			(at 2.050034 -9.774936 270)
			(size 0.519938 1.4986)
			(layers "F.Cu" "F.Mask" "F.Paste")
			(net "GND")
		)
		(pad "209" smd rect
			(at 2.050034 -8.925052 270)
			(size 0.519938 1.4986)
			(layers "F.Cu" "F.Mask" "F.Paste")
			(net "M_F_CPU0_SA_CS_N<3>")
		)
		(pad "210" smd rect
			(at 2.050034 -8.074914 270)
			(size 0.519938 1.4986)
			(layers "F.Cu" "F.Mask" "F.Paste")
			(net "GND")
		)
		(pad "211" smd rect
			(at 2.050034 -7.22503 270)
			(size 0.519938 1.4986)
			(layers "F.Cu" "F.Mask" "F.Paste")
			(net "M_F_CPU0_SA_CA<1>")
		)
		(pad "212" smd rect
			(at 2.050034 -6.374892 270)
			(size 0.519938 1.4986)
			(layers "F.Cu" "F.Mask" "F.Paste")
			(net "GND")
		)
		(pad "213" smd rect
			(at 2.050034 -5.525008 270)
			(size 0.519938 1.4986)
			(layers "F.Cu" "F.Mask" "F.Paste")
			(net "M_F_CPU0_SA_CA<3>")
		)
		(pad "214" smd rect
			(at 2.050034 -4.675124 270)
			(size 0.519938 1.4986)
			(layers "F.Cu" "F.Mask" "F.Paste")
			(net "GND")
		)
		(pad "215" smd rect
			(at 2.050034 -3.824986 270)
			(size 0.519938 1.4986)
			(layers "F.Cu" "F.Mask" "F.Paste")
			(net "M_F_CPU0_SA_CA<5>")
		)
		(pad "216" smd rect
			(at 2.050034 -2.975102 270)
			(size 0.519938 1.4986)
			(layers "F.Cu" "F.Mask" "F.Paste")
			(net "GND")
		)
		(pad "217" smd rect
			(at 2.050034 -2.124964 270)
			(size 0.519938 1.4986)
			(layers "F.Cu" "F.Mask" "F.Paste")
			(net "M_F_CPU0_CLK_DP<1>")
		)
		(pad "218" smd rect
			(at 2.050034 -1.27508 270)
			(size 0.519938 1.4986)
			(layers "F.Cu" "F.Mask" "F.Paste")
			(net "M_F_CPU0_CLK_DN<1>")
		)
		(pad "219" smd rect
			(at 2.050034 -0.424942 270)
			(size 0.519938 1.4986)
			(layers "F.Cu" "F.Mask" "F.Paste")
			(net "GND")
		)
		(pad "220" smd rect
			(at 2.050034 5.525008 270)
			(size 0.519938 1.4986)
			(layers "F.Cu" "F.Mask" "F.Paste")
			(net "TP_CHF_CPU0_DIMM2_FRU_4")
		)
		(pad "221" smd rect
			(at 2.050034 6.374892 270)
			(size 0.519938 1.4986)
			(layers "F.Cu" "F.Mask" "F.Paste")
			(net "M_F_CPU0_SB_CA<1>")
		)
		(pad "222" smd rect
			(at 2.050034 7.22503 270)
			(size 0.519938 1.4986)
			(layers "F.Cu" "F.Mask" "F.Paste")
			(net "GND")
		)
		(pad "223" smd rect
			(at 2.050034 8.074914 270)
			(size 0.519938 1.4986)
			(layers "F.Cu" "F.Mask" "F.Paste")
			(net "M_F_CPU0_SB_CA<3>")
		)
		(pad "224" smd rect
			(at 2.050034 8.925052 270)
			(size 0.519938 1.4986)
			(layers "F.Cu" "F.Mask" "F.Paste")
			(net "GND")
		)
	)
)
